# BASEBOARD_FAB2 (Tioga Pass) — schematic netlist excerpt (pin names and nets, part order shuffled) for the footprints in the layout excerpt that follows; sources: Cadence DE-HDL packaged netlist, KiCad conversion of Wiwynn_Tioga_Pass_MB.brd

J4B1  SCONN288_H44441004  SCONN  pkg PIP  page 49
  \12v\(1)  = P12V_NVDIMM_DEF
  VSS(93)  = GND
  DQ(4)  = M_D_DQ<5>
  VSS(92)  = GND
  DQ(0)  = M_D_DQ<1>
  VSS(91)  = GND
  DQS9P  = M_D_DQS_DP<9>
  DQS9N  = M_D_DQS_DN<9>
  VSS(90)  = GND
  DQ(6)  = M_D_DQ<7>
  VSS(89)  = GND
  DQ(2)  = M_D_DQ<3>
  VSS(88)  = GND
  DQ(12)  = M_D_DQ<13>
  VSS(87)  = GND
  DQ(8)  = M_D_DQ<9>
  VSS(86)  = GND
  DQS10P  = M_D_DQS_DP<10>
  DQS10N  = M_D_DQS_DN<10>
  VSS(85)  = GND
  DQ(14)  = M_D_DQ<15>
  VSS(84)  = GND
  DQ(10)  = M_D_DQ<11>
  VSS(83)  = GND
  DQ(20)  = M_D_DQ<21>
  VSS(82)  = GND
  DQ(16)  = M_D_DQ<17>
  VSS(81)  = GND
  DQS11P  = M_D_DQS_DP<11>
  DQS11N  = M_D_DQS_DN<11>
  VSS(80)  = GND
  DQ(22)  = M_D_DQ<23>
  VSS(79)  = GND
  DQ(18)  = M_D_DQ<19>
  VSS(78)  = GND
  DQ(28)  = M_D_DQ<29>
  VSS(77)  = GND
  DQ(24)  = M_D_DQ<25>
  VSS(76)  = GND
  DQS12P  = M_D_DQS_DP<12>
  DQS12N  = M_D_DQS_DN<12>
  VSS(75)  = GND
  DQ(30)  = M_D_DQ<31>
  VSS(74)  = GND
  DQ(26)  = M_D_DQ<27>
  VSS(73)  = GND
  CB(4)  = M_D_ECC<5>
  VSS(72)  = GND
  CB(0)  = M_D_ECC<1>
  VSS(71)  = GND
  DQS17P  = M_D_DQS_DP<17>
  DQS17N  = M_D_DQS_DN<17>
  VSS(70)  = GND
  CB(6)  = M_D_ECC<7>
  VSS(69)  = GND
  CB(2)  = M_D_ECC<3>
  VSS(68)  = GND
  RESET_N  = M_DEF_RST_N
  VDD(25)  = PVDDQ_DEF
  CKE(0)  = M_D_CKE<0>
  VDD(24)  = PVDDQ_DEF
  ACT_N  = M_D_ACT_N
  BG(0)  = M_D_BG<0>
  VDD(23)  = PVDDQ_DEF
  A12  = M_D_MA<12>
  A9  = M_D_MA<9>
  VDD(22)  = PVDDQ_DEF
  A8  = M_D_MA<8>
  A6  = M_D_MA<6>
  VDD(21)  = PVDDQ_DEF
  A3  = M_D_MA<3>
  A1  = M_D_MA<1>
  VDD(20)  = PVDDQ_DEF
  CK0P  = M_D_CLK_DP<0>
  CK0N  = M_D_CLK_DN<0>
  VDD(19)  = PVDDQ_DEF
  VTT(1)  = PVTT_DEF
  EVENT_N  = FM_DIMM_EVENT_COD_N
  A0  = M_D_MA<0>
  VDD(18)  = PVDDQ_DEF
  BA(0)  = M_D_BA<0>
  A16_RAS_N  = M_D_MA<16>
  VDD(17)  = PVDDQ_DEF
  S0_N  = M_D_CS_N<0>
  VDD(16)  = PVDDQ_DEF
  A15_CAS_N  = M_D_MA<15>
  ODT(0)  = M_D_ODT<0>
  VDD(15)  = PVDDQ_DEF
  S1_N  = M_D_CS_N<1>
  VDD(14)  = PVDDQ_DEF
  ODT(1)  = M_D_ODT<1>
  VDD(13)  = PVDDQ_DEF
  S2_N_C(0)  = M_D_CS_N<2>
  VSS(67)  = GND
  DQ(36)  = M_D_DQ<37>
  VSS(66)  = GND
  DQ(32)  = M_D_DQ<33>
  VSS(65)  = GND
  DQS13P  = M_D_DQS_DP<13>
  DQS13N  = M_D_DQS_DN<13>
  VSS(64)  = GND
  DQ(38)  = M_D_DQ<39>
  VSS(63)  = GND
  DQ(34)  = M_D_DQ<35>
  VSS(62)  = GND
  DQ(44)  = M_D_DQ<45>
  VSS(61)  = GND
  DQ(40)  = M_D_DQ<41>
  VSS(60)  = GND
  DQS14P  = M_D_DQS_DP<14>
  DQS14N  = M_D_DQS_DN<14>
  VSS(59)  = GND
  DQ(46)  = M_D_DQ<47>
  VSS(58)  = GND
  DQ(42)  = M_D_DQ<43>
  VSS(57)  = GND
  DQ(52)  = M_D_DQ<53>
  VSS(56)  = GND
  DQ(48)  = M_D_DQ<49>
  VSS(55)  = GND
  DQS15P  = M_D_DQS_DP<15>
  DQS15N  = M_D_DQS_DN<15>
  VSS(54)  = GND
  DQ(54)  = M_D_DQ<55>
  VSS(53)  = GND
  DQ(50)  = M_D_DQ<51>
  VSS(52)  = GND
  DQ(60)  = M_D_DQ<61>
  VSS(51)  = GND
  DQ(56)  = M_D_DQ<57>
  VSS(50)  = GND
  DQS16P  = M_D_DQS_DP<16>
  DQS16N  = M_D_DQS_DN<16>
  VSS(49)  = GND
  DQ(62)  = M_D_DQ<63>
  VSS(48)  = GND
  DQ(58)  = M_D_DQ<59>
  VSS(47)  = GND
  SA(0)  = GND
  SA(1)  = GND
  SCL  = SMB_DDR_DEF_VPP_SCL
  VPP(4)  = PVPP_DEF
  VPP(3)  = PVPP_DEF
  RFU(2)  = TP_CH_D_DIMM_D0_RFU_2
  \12v\(0)  = P12V_NVDIMM_DEF
  VREFCA  = M_D_VREF
  VSS(46)  = GND
  DQ(5)  = M_D_DQ<4>
  VSS(45)  = GND
  DQ(1)  = M_D_DQ<0>
  VSS(44)  = GND
  DQS0N  = M_D_DQS_DN<0>
  DQS0P  = M_D_DQS_DP<0>
  VSS(43)  = GND
  DQ(7)  = M_D_DQ<6>
  VSS(42)  = GND
  DQ(3)  = M_D_DQ<2>
  VSS(41)  = GND
  DQ(13)  = M_D_DQ<12>
  VSS(40)  = GND
  DQ(9)  = M_D_DQ<8>
  VSS(39)  = GND
  DQS1N  = M_D_DQS_DN<1>
  DQS1P  = M_D_DQS_DP<1>
  VSS(38)  = GND
  DQ(15)  = M_D_DQ<14>
  VSS(37)  = GND
  DQ(11)  = M_D_DQ<10>
  VSS(36)  = GND
  DQ(21)  = M_D_DQ<20>
  VSS(35)  = GND
  DQ(17)  = M_D_DQ<16>
  VSS(34)  = GND
  DQS2N  = M_D_DQS_DN<2>
  DQS2P  = M_D_DQS_DP<2>
  VSS(33)  = GND
  DQ(23)  = M_D_DQ<22>
  VSS(32)  = GND
  DQ(19)  = M_D_DQ<18>
  VSS(31)  = GND
  DQ(29)  = M_D_DQ<28>
  VSS(30)  = GND
  DQ(25)  = M_D_DQ<24>
  VSS(29)  = GND
  DQS3N  = M_D_DQS_DN<3>
  DQS3P  = M_D_DQS_DP<3>
  VSS(28)  = GND
  DQ(31)  = M_D_DQ<30>
  VSS(27)  = GND
  DQ(27)  = M_D_DQ<26>
  VSS(26)  = GND
  CB(5)  = M_D_ECC<4>
  VSS(25)  = GND
  CB(1)  = M_D_ECC<0>
  VSS(24)  = GND
  DQS8N  = M_D_DQS_DN<8>
  DQS8P  = M_D_DQS_DP<8>
  VSS(23)  = GND
  CB(7)  = M_D_ECC<6>
  VSS(22)  = GND
  CB(3)  = M_D_ECC<2>
  VSS(21)  = GND
  CKE(1)  = M_D_CKE<1>
  VDD(12)  = PVDDQ_DEF
  RFU(0)  = TP_CH_D_DIMM_D0_RFU_0
  VDD(11)  = PVDDQ_DEF
  BG(1)  = M_D_BG<1>
  ALERT_N  = M_D_ALERT_N
  VDD(10)  = PVDDQ_DEF
  A11  = M_D_MA<11>
  A7  = M_D_MA<7>
  VDD(9)  = PVDDQ_DEF
  A5  = M_D_MA<5>
  A4  = M_D_MA<4>
  VDD(8)  = PVDDQ_DEF
  A2  = M_D_MA<2>
  VDD(7)  = PVDDQ_DEF
  CK1P  = M_D_CLK_DP<1>
  CK1N  = M_D_CLK_DN<1>
  VDD(6)  = PVDDQ_DEF
  VTT(0)  = PVTT_DEF
  PAR  = M_D_PAR
  VDD(5)  = PVDDQ_DEF
  BA(1)  = M_D_BA<1>
  A10  = M_D_MA<10>
  VDD(4)  = PVDDQ_DEF
  RFU(1)  = TP_CH_D_DIMM_D0_RFU_1
  A14_WE_N  = M_D_MA<14>
  VDD(3)  = PVDDQ_DEF
  SAVE_N_NC  = FM_ADR_COMPLETE_DEF_N
  VDD(2)  = PVDDQ_DEF
  A13  = M_D_MA<13>
  VDD(1)  = PVDDQ_DEF
  A17  = M_D_MA<17>
  C(2)  = M_D_C<2>
  VDD(0)  = PVDDQ_DEF
  S3_N_C(1)  = M_D_CS_N<3>
  SA(2)  = GND
  VSS(20)  = GND
  DQ(37)  = M_D_DQ<36>
  VSS(19)  = GND
  DQ(33)  = M_D_DQ<32>
  VSS(18)  = GND
  DQS4N  = M_D_DQS_DN<4>
  DQS4P  = M_D_DQS_DP<4>
  VSS(17)  = GND
  DQ(39)  = M_D_DQ<38>
  VSS(16)  = GND
  DQ(35)  = M_D_DQ<34>
  VSS(15)  = GND
  DQ(45)  = M_D_DQ<44>
  VSS(14)  = GND
  DQ(41)  = M_D_DQ<40>
  VSS(13)  = GND
  DQS5N  = M_D_DQS_DN<5>
  DQS5P  = M_D_DQS_DP<5>
  VSS(12)  = GND
  DQ(47)  = M_D_DQ<46>
  VSS(11)  = GND
  DQ(43)  = M_D_DQ<42>
  VSS(10)  = GND
  DQ(53)  = M_D_DQ<52>
  VSS(9)  = GND
  DQ(49)  = M_D_DQ<48>
  VSS(8)  = GND
  DQS6N  = M_D_DQS_DN<6>
  DQS6P  = M_D_DQS_DP<6>
  VSS(7)  = GND
  DQ(55)  = M_D_DQ<54>
  VSS(6)  = GND
  DQ(51)  = M_D_DQ<50>
  VSS(5)  = GND
  DQ(61)  = M_D_DQ<60>
  VSS(4)  = GND
  DQ(57)  = M_D_DQ<56>
  VSS(3)  = GND
  DQS7N  = M_D_DQS_DN<7>
  DQS7P  = M_D_DQS_DP<7>
  VSS(2)  = GND
  DQ(63)  = M_D_DQ<62>
  VSS(1)  = GND
  DQ(59)  = M_D_DQ<58>
  VSS(0)  = GND
  VDDSPD  = PVPP_DEF
  SDA  = SMB_DDR_DEF_VPP_SDA
  VPP(1)  = PVPP_DEF
  VPP(0)  = PVPP_DEF
  VPP(2)  = PVPP_DEF

(kicad_pcb
	(version 20260206)
	(generator "pcbnew")
	(generator_version "10.0")
	(general
		(thickness 1.6)
		(legacy_teardrops no)
	)
	(paper "A4")
	(title_block
		(title "Wiwynn_Tioga_Pass_MB.brd")
		(comment 1 "Tioga Pass / footprint 990 of 4770 (J4B1), pads 52-101 of 291")
	)
	(layers
		(0 "F.Cu" signal "TOP")
		(4 "In1.Cu" signal "L2GND")
		(6 "In2.Cu" signal "L3")
		(8 "In3.Cu" signal "L4GND")
		(10 "In4.Cu" signal "L5")
		(12 "In5.Cu" signal "L6GND")
		(14 "In6.Cu" signal "L7VCC")
		(16 "In7.Cu" signal "L8VCC")
		(18 "In8.Cu" signal "L9GND")
		(20 "In9.Cu" signal "L10")
		(22 "In10.Cu" signal "L11GND")
		(24 "In11.Cu" signal "L12")
		(26 "In12.Cu" signal "L13GND")
		(2 "B.Cu" signal "BOTTOM")
		(9 "F.Adhes" user "F.Adhesive")
		(11 "B.Adhes" user "B.Adhesive")
		(13 "F.Paste" user "Package Geometry/Pastemask Top")
		(15 "B.Paste" user "Package Geometry/Pastemask Bottom")
		(5 "F.SilkS" user "Ref Des/Silkscreen Top")
		(7 "B.SilkS" user "Ref Des/Silkscreen Bottom")
		(1 "F.Mask" user "Board Geometry/Soldermask Top")
		(3 "B.Mask" user "Board Geometry/Soldermask Bottom")
		(17 "Dwgs.User" user "User.Drawings")
		(19 "Cmts.User" user "User.Comments")
		(21 "Eco1.User" user "User.Eco1")
		(23 "Eco2.User" user "User.Eco2")
		(25 "Edge.Cuts" user "Board Geometry/Outline")
		(27 "Margin" user)
		(31 "F.CrtYd" user "Package Geometry/Place Bound Top")
		(29 "B.CrtYd" user "Package Geometry/Place Bound Bottom")
		(35 "F.Fab" user "Ref Des/Assembly Top")
		(33 "B.Fab" user "Ref Des/Assembly Bottom")
	)
	(footprint ""
		(layer "F.Cu")
		(at 194.700398 -133.0706 90)
		(property "Reference" "J4B1"
			(at -5.087112 42.28211 0)
			(unlocked yes)
			(layer "F.SilkS")
			(effects
				(font
					(size 0.7874 0.5842)
					(thickness 0.1524)
				)
				(justify left)
			)
		)
		(property "Value" ""
			(at 0 0 90)
			(layer "F.Fab")
			(effects
				(font
					(size 1.27 1.27)
				)
			)
		)
		(duplicate_pad_numbers_are_jumpers no)
		(pad "49" smd rect
			(at 0 40.80002 90)
			(size 1.8034 0.508)
			(layers "F.Cu" "F.Mask" "F.Paste")
			(net "M_D_ECC<1>")
		)
		(pad "50" smd rect
			(at 0 41.649904 90)
			(size 1.8034 0.508)
			(layers "F.Cu" "F.Mask" "F.Paste")
			(net "GND")
		)
		(pad "51" smd rect
			(at 0 42.500042 90)
			(size 1.8034 0.508)
			(layers "F.Cu" "F.Mask" "F.Paste")
			(net "M_D_DQS_DP<17>")
		)
		(pad "52" smd rect
			(at 0 43.349926 90)
			(size 1.8034 0.508)
			(layers "F.Cu" "F.Mask" "F.Paste")
			(net "M_D_DQS_DN<17>")
		)
		(pad "53" smd rect
			(at 0 44.200064 90)
			(size 1.8034 0.508)
			(layers "F.Cu" "F.Mask" "F.Paste")
			(net "GND")
		)
		(pad "54" smd rect
			(at 0 45.049948 90)
			(size 1.8034 0.508)
			(layers "F.Cu" "F.Mask" "F.Paste")
			(net "M_D_ECC<7>")
		)
		(pad "55" smd rect
			(at 0 45.900086 90)
			(size 1.8034 0.508)
			(layers "F.Cu" "F.Mask" "F.Paste")
			(net "GND")
		)
		(pad "56" smd rect
			(at 0 46.74997 90)
			(size 1.8034 0.508)
			(layers "F.Cu" "F.Mask" "F.Paste")
			(net "M_D_ECC<3>")
		)
		(pad "57" smd rect
			(at 0 47.600108 90)
			(size 1.8034 0.508)
			(layers "F.Cu" "F.Mask" "F.Paste")
			(net "GND")
		)
		(pad "58" smd rect
			(at 0 48.449992 90)
			(size 1.8034 0.508)
			(layers "F.Cu" "F.Mask" "F.Paste")
			(net "M_DEF_RST_N")
		)
		(pad "59" smd rect
			(at 0 49.299876 90)
			(size 1.8034 0.508)
			(layers "F.Cu" "F.Mask" "F.Paste")
			(net "PVDDQ_DEF")
		)
		(pad "60" smd rect
			(at 0 50.150014 90)
			(size 1.8034 0.508)
			(layers "F.Cu" "F.Mask" "F.Paste")
			(net "M_D_CKE<0>")
		)
		(pad "61" smd rect
			(at 0 50.999898 90)
			(size 1.8034 0.508)
			(layers "F.Cu" "F.Mask" "F.Paste")
			(net "PVDDQ_DEF")
		)
		(pad "62" smd rect
			(at 0 51.850036 90)
			(size 1.8034 0.508)
			(layers "F.Cu" "F.Mask" "F.Paste")
			(net "M_D_ACT_N")
		)
		(pad "63" smd rect
			(at 0 52.69992 90)
			(size 1.8034 0.508)
			(layers "F.Cu" "F.Mask" "F.Paste")
			(net "M_D_BG<0>")
		)
		(pad "64" smd rect
			(at 0 53.550058 90)
			(size 1.8034 0.508)
			(layers "F.Cu" "F.Mask" "F.Paste")
			(net "PVDDQ_DEF")
		)
		(pad "65" smd rect
			(at 0 54.399942 90)
			(size 1.8034 0.508)
			(layers "F.Cu" "F.Mask" "F.Paste")
			(net "M_D_MA<12>")
		)
		(pad "66" smd rect
			(at 0 55.25008 90)
			(size 1.8034 0.508)
			(layers "F.Cu" "F.Mask" "F.Paste")
			(net "M_D_MA<9>")
		)
		(pad "67" smd rect
			(at 0 56.099964 90)
			(size 1.8034 0.508)
			(layers "F.Cu" "F.Mask" "F.Paste")
			(net "PVDDQ_DEF")
		)
		(pad "68" smd rect
			(at 0 56.950102 90)
			(size 1.8034 0.508)
			(layers "F.Cu" "F.Mask" "F.Paste")
			(net "M_D_MA<8>")
		)
		(pad "69" smd rect
			(at 0 57.799986 90)
			(size 1.8034 0.508)
			(layers "F.Cu" "F.Mask" "F.Paste")
			(net "M_D_MA<6>")
		)
		(pad "70" smd rect
			(at 0 58.650124 90)
			(size 1.8034 0.508)
			(layers "F.Cu" "F.Mask" "F.Paste")
			(net "PVDDQ_DEF")
		)
		(pad "71" smd rect
			(at 0 59.500008 90)
			(size 1.8034 0.508)
			(layers "F.Cu" "F.Mask" "F.Paste")
			(net "M_D_MA<3>")
		)
		(pad "72" smd rect
			(at 0 60.349892 90)
			(size 1.8034 0.508)
			(layers "F.Cu" "F.Mask" "F.Paste")
			(net "M_D_MA<1>")
		)
		(pad "73" smd rect
			(at 0 61.20003 90)
			(size 1.8034 0.508)
			(layers "F.Cu" "F.Mask" "F.Paste")
			(net "PVDDQ_DEF")
		)
		(pad "74" smd rect
			(at 0 62.049914 90)
			(size 1.8034 0.508)
			(layers "F.Cu" "F.Mask" "F.Paste")
			(net "M_D_CLK_DP<0>")
		)
		(pad "75" smd rect
			(at 0 62.900052 90)
			(size 1.8034 0.508)
			(layers "F.Cu" "F.Mask" "F.Paste")
			(net "M_D_CLK_DN<0>")
		)
		(pad "76" smd rect
			(at 0 63.749936 90)
			(size 1.8034 0.508)
			(layers "F.Cu" "F.Mask" "F.Paste")
			(net "PVDDQ_DEF")
		)
		(pad "77" smd rect
			(at 0 64.600074 90)
			(size 1.8034 0.508)
			(layers "F.Cu" "F.Mask" "F.Paste")
			(net "PVTT_DEF")
		)
		(pad "78" smd rect
			(at 0 70.550024 90)
			(size 1.8034 0.508)
			(layers "F.Cu" "F.Mask" "F.Paste")
			(net "FM_DIMM_EVENT_COD_N")
		)
		(pad "79" smd rect
			(at 0 71.399908 90)
			(size 1.8034 0.508)
			(layers "F.Cu" "F.Mask" "F.Paste")
			(net "M_D_MA<0>")
		)
		(pad "80" smd rect
			(at 0 72.250046 90)
			(size 1.8034 0.508)
			(layers "F.Cu" "F.Mask" "F.Paste")
			(net "PVDDQ_DEF")
		)
		(pad "81" smd rect
			(at 0 73.09993 90)
			(size 1.8034 0.508)
			(layers "F.Cu" "F.Mask" "F.Paste")
			(net "M_D_BA<0>")
		)
		(pad "82" smd rect
			(at 0 73.950068 90)
			(size 1.8034 0.508)
			(layers "F.Cu" "F.Mask" "F.Paste")
			(net "M_D_MA<16>")
		)
		(pad "83" smd rect
			(at 0 74.799952 90)
			(size 1.8034 0.508)
			(layers "F.Cu" "F.Mask" "F.Paste")
			(net "PVDDQ_DEF")
		)
		(pad "84" smd rect
			(at 0 75.65009 90)
			(size 1.8034 0.508)
			(layers "F.Cu" "F.Mask" "F.Paste")
			(net "M_D_CS_N<0>")
		)
		(pad "85" smd rect
			(at 0 76.499974 90)
			(size 1.8034 0.508)
			(layers "F.Cu" "F.Mask" "F.Paste")
			(net "PVDDQ_DEF")
		)
		(pad "86" smd rect
			(at 0 77.350112 90)
			(size 1.8034 0.508)
			(layers "F.Cu" "F.Mask" "F.Paste")
			(net "M_D_MA<15>")
		)
		(pad "87" smd rect
			(at 0 78.199996 90)
			(size 1.8034 0.508)
			(layers "F.Cu" "F.Mask" "F.Paste")
			(net "M_D_ODT<0>")
		)
		(pad "88" smd rect
			(at 0 79.04988 90)
			(size 1.8034 0.508)
			(layers "F.Cu" "F.Mask" "F.Paste")
			(net "PVDDQ_DEF")
		)
		(pad "89" smd rect
			(at 0 79.900018 90)
			(size 1.8034 0.508)
			(layers "F.Cu" "F.Mask" "F.Paste")
			(net "M_D_CS_N<1>")
		)
		(pad "90" smd rect
			(at 0 80.749902 90)
			(size 1.8034 0.508)
			(layers "F.Cu" "F.Mask" "F.Paste")
			(net "PVDDQ_DEF")
		)
		(pad "91" smd rect
			(at 0 81.60004 90)
			(size 1.8034 0.508)
			(layers "F.Cu" "F.Mask" "F.Paste")
			(net "M_D_ODT<1>")
		)
		(pad "92" smd rect
			(at 0 82.449924 90)
			(size 1.8034 0.508)
			(layers "F.Cu" "F.Mask" "F.Paste")
			(net "PVDDQ_DEF")
		)
		(pad "93" smd rect
			(at 0 83.300062 90)
			(size 1.8034 0.508)
			(layers "F.Cu" "F.Mask" "F.Paste")
			(net "M_D_CS_N<2>")
		)
		(pad "94" smd rect
			(at 0 84.149946 90)
			(size 1.8034 0.508)
			(layers "F.Cu" "F.Mask" "F.Paste")
			(net "GND")
		)
		(pad "95" smd rect
			(at 0 85.000084 90)
			(size 1.8034 0.508)
			(layers "F.Cu" "F.Mask" "F.Paste")
			(net "M_D_DQ<37>")
		)
		(pad "96" smd rect
			(at 0 85.849968 90)
			(size 1.8034 0.508)
			(layers "F.Cu" "F.Mask" "F.Paste")
			(net "GND")
		)
		(pad "97" smd rect
			(at 0 86.700106 90)
			(size 1.8034 0.508)
			(layers "F.Cu" "F.Mask" "F.Paste")
			(net "M_D_DQ<33>")
		)
		(pad "98" smd rect
			(at 0 87.54999 90)
			(size 1.8034 0.508)
			(layers "F.Cu" "F.Mask" "F.Paste")
			(net "GND")
		)
	)
)
